# SCM (Grand Teton) — schematic netlist excerpt (pin names and nets, part order shuffled) for the footprints in the layout excerpt that follows; sources: Cadence DE-HDL packaged netlist, KiCad conversion of 12092022_DA0F0TMDCD0_F0T_Management_Board_D_brd_V3_OCP.brd

C138  Q_CAP  0.01UF 50V 10% X7R  pkg C0402  page 17 : A = A_BMC_ADCVREFN0 ; B = A_BMC_ADCVREFP0
R452  Q_RES  4.7K 1% CHIP  pkg 0402LF  page 13 : A = P3V3_AUX ; B = RST_WDTRST_PLD_N

(kicad_pcb
	(version 20260206)
	(generator "pcbnew")
	(generator_version "10.0")
	(general
		(thickness 1.6)
		(legacy_teardrops no)
	)
	(paper "A4")
	(title_block
		(title "12092022_DA0F0TMDCD0_F0T_Management_Board_D_brd_V3_OCP.brd")
		(comment 1 "Grand Teton / footprints 1419-1420 of 1440")
	)
	(layers
		(0 "F.Cu" signal "TOP")
		(4 "In1.Cu" signal "GND")
		(6 "In2.Cu" signal "IN1")
		(8 "In3.Cu" signal "GND1")
		(10 "In4.Cu" signal "IN2")
		(12 "In5.Cu" signal "VCC")
		(14 "In6.Cu" signal "VCC1")
		(16 "In7.Cu" signal "IN3")
		(18 "In8.Cu" signal "GND2")
		(20 "In9.Cu" signal "IN4")
		(22 "In10.Cu" signal "GND3")
		(2 "B.Cu" signal "BOTTOM")
		(9 "F.Adhes" user "F.Adhesive")
		(11 "B.Adhes" user "B.Adhesive")
		(13 "F.Paste" user "Package Geometry/Pastemask Top")
		(15 "B.Paste" user "Package Geometry/Pastemask Bottom")
		(5 "F.SilkS" user "Ref Des/Silkscreen Top")
		(7 "B.SilkS" user "Ref Des/Silkscreen Bottom")
		(1 "F.Mask" user "Board Geometry/Soldermask Top")
		(3 "B.Mask" user "Board Geometry/Soldermask Bottom")
		(17 "Dwgs.User" user "User.Drawings")
		(19 "Cmts.User" user "User.Comments")
		(21 "Eco1.User" user "User.Eco1")
		(23 "Eco2.User" user "User.Eco2")
		(25 "Edge.Cuts" user "Board Geometry/Outline")
		(27 "Margin" user)
		(31 "F.CrtYd" user "Package Geometry/Place Bound Top")
		(29 "B.CrtYd" user "Package Geometry/Place Bound Bottom")
		(35 "F.Fab" user "Ref Des/Assembly Top")
		(33 "B.Fab" user "Ref Des/Assembly Bottom")
	)
	(footprint ""
		(layer "B.Cu")
		(at 46.577758 -60.564776 180)
		(property "Reference" "C138"
			(at 0 0 0)
			(layer "B.SilkS")
			(hide yes)
			(effects
				(font
					(size 1.27 1.27)
				)
				(justify mirror)
			)
		)
		(property "Value" ""
			(at 0 0 0)
			(layer "B.Fab")
			(effects
				(font
					(size 1.27 1.27)
				)
				(justify mirror)
			)
		)
		(duplicate_pad_numbers_are_jumpers no)
		(fp_line
			(start 0.7874 0.4064)
			(end 0.7874 -0.4064)
			(stroke
				(width 0.1524)
				(type default)
			)
			(layer "B.SilkS")
		)
		(fp_line
			(start 0.7874 -0.4064)
			(end -0.7874 -0.4064)
			(stroke
				(width 0.1524)
				(type default)
			)
			(layer "B.SilkS")
		)
		(fp_line
			(start -0.7874 0.4064)
			(end 0.7874 0.4064)
			(stroke
				(width 0.1524)
				(type default)
			)
			(layer "B.SilkS")
		)
		(fp_line
			(start -0.7874 -0.4064)
			(end -0.7874 0.4064)
			(stroke
				(width 0.1524)
				(type default)
			)
			(layer "B.SilkS")
		)
		(fp_line
			(start 0.67945 0.3048)
			(end 0.67945 -0.305054)
			(stroke
				(width 0.1)
				(type default)
			)
			(layer "B.Fab")
		)
		(fp_line
			(start 0.67945 -0.305054)
			(end 0.12065 -0.305054)
			(stroke
				(width 0.1)
				(type default)
			)
			(layer "B.Fab")
		)
		(fp_line
			(start 0.12065 0.3048)
			(end 0.67945 0.3048)
			(stroke
				(width 0.1)
				(type default)
			)
			(layer "B.Fab")
		)
		(fp_line
			(start 0.12065 0.2794)
			(end 0.12065 0.3048)
			(stroke
				(width 0.1)
				(type default)
			)
			(layer "B.Fab")
		)
		(fp_line
			(start 0.12065 -0.2794)
			(end -0.12065 -0.2794)
			(stroke
				(width 0.1)
				(type default)
			)
			(layer "B.Fab")
		)
		(fp_line
			(start 0.12065 -0.305054)
			(end 0.12065 -0.2794)
			(stroke
				(width 0.1)
				(type default)
			)
			(layer "B.Fab")
		)
		(fp_line
			(start -0.120396 0.3048)
			(end -0.120396 0.2794)
			(stroke
				(width 0.1)
				(type default)
			)
			(layer "B.Fab")
		)
		(fp_line
			(start -0.120396 0.2794)
			(end 0.12065 0.2794)
			(stroke
				(width 0.1)
				(type default)
			)
			(layer "B.Fab")
		)
		(fp_line
			(start -0.12065 -0.2794)
			(end -0.12065 -0.3048)
			(stroke
				(width 0.1)
				(type default)
			)
			(layer "B.Fab")
		)
		(fp_line
			(start -0.12065 -0.3048)
			(end -0.67945 -0.3048)
			(stroke
				(width 0.1)
				(type default)
			)
			(layer "B.Fab")
		)
		(fp_line
			(start -0.67945 0.3048)
			(end -0.120396 0.3048)
			(stroke
				(width 0.1)
				(type default)
			)
			(layer "B.Fab")
		)
		(fp_line
			(start -0.67945 -0.3048)
			(end -0.67945 0.3048)
			(stroke
				(width 0.1)
				(type default)
			)
			(layer "B.Fab")
		)
		(pad "1" smd circle
			(at 0.40005 0)
			(size 0 0)
			(layers "B.Cu" "B.Mask" "B.Paste")
			(net "A_BMC_ADCVREFN0")
		)
		(pad "2" smd circle
			(at -0.40005 0)
			(size 0 0)
			(layers "B.Cu" "B.Mask" "B.Paste")
			(net "A_BMC_ADCVREFP0")
		)
	)
	(footprint ""
		(layer "B.Cu")
		(at 54.3814 -65.3288 90)
		(property "Reference" "R452"
			(at 0 0 90)
			(layer "B.SilkS")
			(hide yes)
			(effects
				(font
					(size 1.27 1.27)
				)
				(justify mirror)
			)
		)
		(property "Value" ""
			(at 0 0 90)
			(layer "B.Fab")
			(effects
				(font
					(size 1.27 1.27)
				)
				(justify mirror)
			)
		)
		(duplicate_pad_numbers_are_jumpers no)
		(fp_line
			(start 0.7874 -0.4064)
			(end -0.7874 -0.4064)
			(stroke
				(width 0.1524)
				(type default)
			)
			(layer "B.SilkS")
		)
		(fp_line
			(start -0.7874 -0.4064)
			(end -0.7874 0.4064)
			(stroke
				(width 0.1524)
				(type default)
			)
			(layer "B.SilkS")
		)
		(fp_line
			(start 0.7874 0.4064)
			(end 0.7874 -0.4064)
			(stroke
				(width 0.1524)
				(type default)
			)
			(layer "B.SilkS")
		)
		(fp_line
			(start -0.7874 0.4064)
			(end 0.7874 0.4064)
			(stroke
				(width 0.1524)
				(type default)
			)
			(layer "B.SilkS")
		)
		(fp_line
			(start 0.67945 -0.305054)
			(end 0.12065 -0.305054)
			(stroke
				(width 0.1)
				(type default)
			)
			(layer "B.Fab")
		)
		(fp_line
			(start 0.12065 -0.305054)
			(end 0.12065 -0.2794)
			(stroke
				(width 0.1)
				(type default)
			)
			(layer "B.Fab")
		)
		(fp_line
			(start -0.12065 -0.3048)
			(end -0.67945 -0.3048)
			(stroke
				(width 0.1)
				(type default)
			)
			(layer "B.Fab")
		)
		(fp_line
			(start -0.67945 -0.3048)
			(end -0.67945 0.3048)
			(stroke
				(width 0.1)
				(type default)
			)
			(layer "B.Fab")
		)
		(fp_line
			(start 0.12065 -0.2794)
			(end -0.12065 -0.2794)
			(stroke
				(width 0.1)
				(type default)
			)
			(layer "B.Fab")
		)
		(fp_line
			(start -0.12065 -0.2794)
			(end -0.12065 -0.3048)
			(stroke
				(width 0.1)
				(type default)
			)
			(layer "B.Fab")
		)
		(fp_line
			(start 0.12065 0.2794)
			(end 0.12065 0.3048)
			(stroke
				(width 0.1)
				(type default)
			)
			(layer "B.Fab")
		)
		(fp_line
			(start -0.120396 0.2794)
			(end 0.12065 0.2794)
			(stroke
				(width 0.1)
				(type default)
			)
			(layer "B.Fab")
		)
		(fp_line
			(start 0.67945 0.3048)
			(end 0.67945 -0.305054)
			(stroke
				(width 0.1)
				(type default)
			)
			(layer "B.Fab")
		)
		(fp_line
			(start 0.12065 0.3048)
			(end 0.67945 0.3048)
			(stroke
				(width 0.1)
				(type default)
			)
			(layer "B.Fab")
		)
		(fp_line
			(start -0.120396 0.3048)
			(end -0.120396 0.2794)
			(stroke
				(width 0.1)
				(type default)
			)
			(layer "B.Fab")
		)
		(fp_line
			(start -0.67945 0.3048)
			(end -0.120396 0.3048)
			(stroke
				(width 0.1)
				(type default)
			)
			(layer "B.Fab")
		)
		(pad "1" smd circle
			(at 0.40005 0 270)
			(size 0 0)
			(layers "B.Cu" "B.Mask" "B.Paste")
			(net "P3V3_AUX")
		)
		(pad "2" smd circle
			(at -0.40005 0 270)
			(size 0 0)
			(layers "B.Cu" "B.Mask" "B.Paste")
			(net "RST_WDTRST_PLD_N")
		)
	)
)
